# BASEBOARD_FAB2 (Tioga Pass) — schematic netlist excerpt (pin names and nets, part order shuffled) for the footprints in the layout excerpt that follows; sources: Cadence DE-HDL packaged netlist, KiCad conversion of Wiwynn_Tioga_Pass_MB.brd

C3A4  CAP  10UF 4V 20% X6S  pkg 0603LF  page 234 : A = PVPP_KLM ; B = GND
C7A12  CAP  0.220UF 16V 10% X7R  pkg 0402  page 219 : A = VR_PVDDQ_DEF_PH1_BOOT ; B = VR_PVDDQ_DEF_PH1_PHASE
R1W30  RES  0.0 5% EMPTY  pkg 0402  page 118 : A = RST_BMC_SYSRST_BTN_OUT_B_N ; B = RST_SYSTEM_BTN_BUF_N

(kicad_pcb
	(version 20260206)
	(generator "pcbnew")
	(generator_version "10.0")
	(general
		(thickness 1.6)
		(legacy_teardrops no)
	)
	(paper "A4")
	(title_block
		(title "Wiwynn_Tioga_Pass_MB.brd")
		(comment 1 "Tioga Pass / footprints 247-249 of 4770")
	)
	(layers
		(0 "F.Cu" signal "TOP")
		(4 "In1.Cu" signal "L2GND")
		(6 "In2.Cu" signal "L3")
		(8 "In3.Cu" signal "L4GND")
		(10 "In4.Cu" signal "L5")
		(12 "In5.Cu" signal "L6GND")
		(14 "In6.Cu" signal "L7VCC")
		(16 "In7.Cu" signal "L8VCC")
		(18 "In8.Cu" signal "L9GND")
		(20 "In9.Cu" signal "L10")
		(22 "In10.Cu" signal "L11GND")
		(24 "In11.Cu" signal "L12")
		(26 "In12.Cu" signal "L13GND")
		(2 "B.Cu" signal "BOTTOM")
		(9 "F.Adhes" user "F.Adhesive")
		(11 "B.Adhes" user "B.Adhesive")
		(13 "F.Paste" user "Package Geometry/Pastemask Top")
		(15 "B.Paste" user "Package Geometry/Pastemask Bottom")
		(5 "F.SilkS" user "Ref Des/Silkscreen Top")
		(7 "B.SilkS" user "Ref Des/Silkscreen Bottom")
		(1 "F.Mask" user "Board Geometry/Soldermask Top")
		(3 "B.Mask" user "Board Geometry/Soldermask Bottom")
		(17 "Dwgs.User" user "User.Drawings")
		(19 "Cmts.User" user "User.Comments")
		(21 "Eco1.User" user "User.Eco1")
		(23 "Eco2.User" user "User.Eco2")
		(25 "Edge.Cuts" user "Board Geometry/Outline")
		(27 "Margin" user)
		(31 "F.CrtYd" user "Package Geometry/Place Bound Top")
		(29 "B.CrtYd" user "Package Geometry/Place Bound Bottom")
		(35 "F.Fab" user "Ref Des/Assembly Top")
		(33 "B.Fab" user "Ref Des/Assembly Bottom")
	)
	(footprint ""
		(layer "F.Cu")
		(at 155.575 -149.606 90)
		(property "Reference" "C3A4"
			(at 0 0 90)
			(layer "F.SilkS")
			(hide yes)
			(effects
				(font
					(size 1.27 1.27)
				)
			)
		)
		(property "Value" ""
			(at 0 0 90)
			(layer "F.Fab")
			(effects
				(font
					(size 1.27 1.27)
				)
			)
		)
		(duplicate_pad_numbers_are_jumpers no)
		(fp_rect
			(start -0.4953 1.6002)
			(end 0.4953 -0.2032)
			(stroke
				(width 0)
				(type default)
			)
			(fill no)
			(layer "F.CrtYd")
		)
		(fp_line
			(start 0.4953 -0.2032)
			(end 0.4953 1.6002)
			(stroke
				(width 0.1)
				(type default)
			)
			(layer "F.Fab")
		)
		(fp_line
			(start -0.4953 -0.2032)
			(end 0.4953 -0.2032)
			(stroke
				(width 0.1)
				(type default)
			)
			(layer "F.Fab")
		)
		(fp_line
			(start 0.4953 1.6002)
			(end -0.4953 1.6002)
			(stroke
				(width 0.1)
				(type default)
			)
			(layer "F.Fab")
		)
		(fp_line
			(start -0.4953 1.6002)
			(end -0.4953 -0.2032)
			(stroke
				(width 0.1)
				(type default)
			)
			(layer "F.Fab")
		)
		(pad "1" smd rect
			(at 0 0 90)
			(size 0.762 0.889)
			(layers "F.Cu" "F.Mask" "F.Paste")
			(net "PVPP_KLM")
		)
		(pad "2" smd rect
			(at 0 1.397 90)
			(size 0.762 0.889)
			(layers "F.Cu" "F.Mask" "F.Paste")
			(net "GND")
		)
		(zone
			(layer "F.Cu")
			(hatch none 0.5)
			(connect_pads
				(clearance 0)
			)
			(min_thickness 0.25)
			(keepout
				(tracks not_allowed)
				(vias allowed)
				(pads allowed)
				(copperpour not_allowed)
				(footprints allowed)
			)
			(placement
				(enabled no)
				(sheetname "")
			)
			(fill
				(thermal_gap 0.5)
				(thermal_bridge_width 0.5)
				(island_removal_mode 0)
			)
			(polygon
				(pts
					(xy 156.5275 -149.225) (xy 156.5275 -149.987) (xy 156.0195 -149.987) (xy 156.0195 -149.225)
				)
			)
		)
	)
	(footprint ""
		(layer "F.Cu")
		(at 415.29 -101.2698 90)
		(property "Reference" "R1W30"
			(at -0.8382 -0.67818 90)
			(unlocked yes)
			(layer "F.SilkS")
			(effects
				(font
					(size 0.4064 0.254)
					(thickness 0.1524)
				)
				(justify left)
			)
		)
		(property "Value" ""
			(at 0 0 90)
			(layer "F.Fab")
			(effects
				(font
					(size 1.27 1.27)
				)
			)
		)
		(duplicate_pad_numbers_are_jumpers no)
		(fp_poly
			(pts
				(xy -0.2794 -0.1016) (xy 0.2794 -0.1016) (xy 0.2794 0.9906) (xy -0.2794 0.9906)
			)
			(stroke
				(width 0)
				(type default)
			)
			(fill no)
			(layer "F.CrtYd")
		)
		(fp_line
			(start 0.2794 -0.1016)
			(end -0.2794 -0.1016)
			(stroke
				(width 0.1)
				(type default)
			)
			(layer "F.Fab")
		)
		(fp_line
			(start -0.2794 -0.1016)
			(end -0.2794 0.9906)
			(stroke
				(width 0.1)
				(type default)
			)
			(layer "F.Fab")
		)
		(fp_line
			(start 0.2794 0.9906)
			(end 0.2794 -0.1016)
			(stroke
				(width 0.1)
				(type default)
			)
			(layer "F.Fab")
		)
		(fp_line
			(start -0.2794 0.9906)
			(end 0.2794 0.9906)
			(stroke
				(width 0.1)
				(type default)
			)
			(layer "F.Fab")
		)
		(pad "1" smd rect
			(at 0 0 90)
			(size 0.508 0.508)
			(layers "F.Cu" "F.Mask" "F.Paste")
			(net "RST_BMC_SYSRST_BTN_OUT_B_N")
		)
		(pad "2" smd rect
			(at 0 0.889 90)
			(size 0.508 0.508)
			(layers "F.Cu" "F.Mask" "F.Paste")
			(net "RST_SYSTEM_BTN_BUF_N")
		)
		(zone
			(layer "F.Cu")
			(hatch none 0.5)
			(connect_pads
				(clearance 0)
			)
			(min_thickness 0.25)
			(keepout
				(tracks allowed)
				(vias not_allowed)
				(pads allowed)
				(copperpour not_allowed)
				(footprints allowed)
			)
			(placement
				(enabled no)
				(sheetname "")
			)
			(fill
				(thermal_gap 0.5)
				(thermal_bridge_width 0.5)
				(island_removal_mode 0)
			)
			(polygon
				(pts
					(xy 415.544 -101.0158) (xy 415.544 -101.5238) (xy 415.925 -101.5238) (xy 415.925 -101.0158)
				)
			)
		)
		(zone
			(layer "F.Cu")
			(hatch none 0.5)
			(connect_pads
				(clearance 0)
			)
			(min_thickness 0.25)
			(keepout
				(tracks not_allowed)
				(vias allowed)
				(pads allowed)
				(copperpour not_allowed)
				(footprints allowed)
			)
			(placement
				(enabled no)
				(sheetname "")
			)
			(fill
				(thermal_gap 0.5)
				(thermal_bridge_width 0.5)
				(island_removal_mode 0)
			)
			(polygon
				(pts
					(xy 415.925 -101.0158) (xy 415.925 -101.5238) (xy 415.544 -101.5238) (xy 415.544 -101.0158)
				)
			)
		)
	)
	(footprint ""
		(layer "F.Cu")
		(at 352.9965 -151.257 -90)
		(property "Reference" "C7A12"
			(at 0 0 270)
			(layer "F.SilkS")
			(hide yes)
			(effects
				(font
					(size 1.27 1.27)
				)
			)
		)
		(property "Value" ""
			(at 0 0 270)
			(layer "F.Fab")
			(effects
				(font
					(size 1.27 1.27)
				)
			)
		)
		(duplicate_pad_numbers_are_jumpers no)
		(fp_poly
			(pts
				(xy 0.3048 -0.1016) (xy 0.3048 0.9906) (xy -0.3048 0.9906) (xy -0.3048 -0.1016)
			)
			(stroke
				(width 0)
				(type default)
			)
			(fill no)
			(layer "F.CrtYd")
		)
		(fp_line
			(start -0.3048 0.9906)
			(end 0.3048 0.9906)
			(stroke
				(width 0.1)
				(type default)
			)
			(layer "F.Fab")
		)
		(fp_line
			(start 0.3048 0.9906)
			(end 0.3048 -0.1016)
			(stroke
				(width 0.1)
				(type default)
			)
			(layer "F.Fab")
		)
		(fp_line
			(start -0.3048 -0.1016)
			(end -0.3048 0.9906)
			(stroke
				(width 0.1)
				(type default)
			)
			(layer "F.Fab")
		)
		(fp_line
			(start 0.3048 -0.1016)
			(end -0.3048 -0.1016)
			(stroke
				(width 0.1)
				(type default)
			)
			(layer "F.Fab")
		)
		(pad "1" smd rect
			(at 0 0 270)
			(size 0.508 0.508)
			(layers "F.Cu" "F.Mask" "F.Paste")
			(net "VR_PVDDQ_DEF_PH1_BOOT")
		)
		(pad "2" smd rect
			(at 0 0.889 270)
			(size 0.508 0.508)
			(layers "F.Cu" "F.Mask" "F.Paste")
			(net "VR_PVDDQ_DEF_PH1_PHASE")
		)
		(zone
			(layer "F.Cu")
			(hatch none 0.5)
			(connect_pads
				(clearance 0)
			)
			(min_thickness 0.25)
			(keepout
				(tracks not_allowed)
				(vias allowed)
				(pads allowed)
				(copperpour not_allowed)
				(footprints allowed)
			)
			(placement
				(enabled no)
				(sheetname "")
			)
			(fill
				(thermal_gap 0.5)
				(thermal_bridge_width 0.5)
				(island_removal_mode 0)
			)
			(polygon
				(pts
					(xy 352.3615 -151.511) (xy 352.3615 -151.003) (xy 352.7425 -151.003) (xy 352.7425 -151.511)
				)
			)
		)
		(zone
			(layer "F.Cu")
			(hatch none 0.5)
			(connect_pads
				(clearance 0)
			)
			(min_thickness 0.25)
			(keepout
				(tracks allowed)
				(vias not_allowed)
				(pads allowed)
				(copperpour not_allowed)
				(footprints allowed)
			)
			(placement
				(enabled no)
				(sheetname "")
			)
			(fill
				(thermal_gap 0.5)
				(thermal_bridge_width 0.5)
				(island_removal_mode 0)
			)
			(polygon
				(pts
					(xy 352.7425 -151.511) (xy 352.7425 -151.003) (xy 352.3615 -151.003) (xy 352.3615 -151.511)
				)
			)
		)
	)
)
